# S9S_MB_2U (Grand Teton) — schematic netlist excerpt (pin names and nets, part order shuffled) for the footprints in the layout excerpt that follows; sources: Cadence DE-HDL packaged netlist, KiCad conversion of 03242023_DA0F0TMBIJ0_F0T_Motherboard_J_brd_V01_OCP.brd

R682  Q_RES  0 5% EMPTY  pkg 0402LF  page 229 : A = I3C_SPD_DDRABCD_CPU0_R_SCL ; B = I3C_SPD_DDRABCD_CPU0_LVC1_R_SCL

X26  TP_TDR_4P_FTS  TP_TDR_4P_DIP EMPTY  pkg TH  page 309
  S1  = TDR_DIFF_85_IN6_DP
  P1  = T1_GND
  P2  = T1_GND
  S2  = TDR_DIFF_85_IN6_DN

(kicad_pcb
	(version 20260206)
	(generator "pcbnew")
	(generator_version "10.0")
	(general
		(thickness 1.6)
		(legacy_teardrops no)
	)
	(paper "A4")
	(title_block
		(title "03242023_DA0F0TMBIJ0_F0T_Motherboard_J_brd_V01_OCP.brd")
		(comment 1 "Grand Teton / footprints 4938-4939 of 6105")
	)
	(layers
		(0 "F.Cu" signal "TOP")
		(4 "In1.Cu" signal "GND")
		(6 "In2.Cu" signal "IN1")
		(8 "In3.Cu" signal "GND1")
		(10 "In4.Cu" signal "IN2")
		(12 "In5.Cu" signal "GND2")
		(14 "In6.Cu" signal "IN3")
		(16 "In7.Cu" signal "GND3")
		(18 "In8.Cu" signal "VCC")
		(20 "In9.Cu" signal "VCC1")
		(22 "In10.Cu" signal "GND4")
		(24 "In11.Cu" signal "IN4")
		(26 "In12.Cu" signal "GND5")
		(28 "In13.Cu" signal "IN5")
		(30 "In14.Cu" signal "GND6")
		(32 "In15.Cu" signal "IN6")
		(34 "In16.Cu" signal "GND7")
		(2 "B.Cu" signal "BOTTOM")
		(9 "F.Adhes" user "F.Adhesive")
		(11 "B.Adhes" user "B.Adhesive")
		(13 "F.Paste" user "Package Geometry/Pastemask Top")
		(15 "B.Paste" user "Package Geometry/Pastemask Bottom")
		(5 "F.SilkS" user "Ref Des/Silkscreen Top")
		(7 "B.SilkS" user "Ref Des/Silkscreen Bottom")
		(1 "F.Mask" user "Board Geometry/Soldermask Top")
		(3 "B.Mask" user "Board Geometry/Soldermask Bottom")
		(17 "Dwgs.User" user "User.Drawings")
		(19 "Cmts.User" user "User.Comments")
		(21 "Eco1.User" user "User.Eco1")
		(23 "Eco2.User" user "User.Eco2")
		(25 "Edge.Cuts" user "Board Geometry/Outline")
		(27 "Margin" user)
		(31 "F.CrtYd" user "Package Geometry/Place Bound Top")
		(29 "B.CrtYd" user "Package Geometry/Place Bound Bottom")
		(35 "F.Fab" user "Ref Des/Assembly Top")
		(33 "B.Fab" user "Ref Des/Assembly Bottom")
	)
	(footprint ""
		(layer "B.Cu")
		(at 292.983158 -151.775668 -90)
		(property "Reference" "R682"
			(at 0 0 90)
			(layer "B.SilkS")
			(hide yes)
			(effects
				(font
					(size 1.27 1.27)
				)
				(justify mirror)
			)
		)
		(property "Value" ""
			(at 0 0 90)
			(layer "B.Fab")
			(effects
				(font
					(size 1.27 1.27)
				)
				(justify mirror)
			)
		)
		(duplicate_pad_numbers_are_jumpers no)
		(fp_line
			(start -0.7874 0.4064)
			(end 0.7874 0.4064)
			(stroke
				(width 0.1524)
				(type default)
			)
			(layer "B.SilkS")
		)
		(fp_line
			(start 0.7874 0.4064)
			(end 0.7874 -0.4064)
			(stroke
				(width 0.1524)
				(type default)
			)
			(layer "B.SilkS")
		)
		(fp_line
			(start -0.7874 -0.4064)
			(end -0.7874 0.4064)
			(stroke
				(width 0.1524)
				(type default)
			)
			(layer "B.SilkS")
		)
		(fp_line
			(start 0.7874 -0.4064)
			(end -0.7874 -0.4064)
			(stroke
				(width 0.1524)
				(type default)
			)
			(layer "B.SilkS")
		)
		(fp_line
			(start -0.67945 0.3048)
			(end -0.120396 0.3048)
			(stroke
				(width 0.1)
				(type default)
			)
			(layer "B.Fab")
		)
		(fp_line
			(start -0.120396 0.3048)
			(end -0.120396 0.2794)
			(stroke
				(width 0.1)
				(type default)
			)
			(layer "B.Fab")
		)
		(fp_line
			(start 0.12065 0.3048)
			(end 0.67945 0.3048)
			(stroke
				(width 0.1)
				(type default)
			)
			(layer "B.Fab")
		)
		(fp_line
			(start 0.67945 0.3048)
			(end 0.67945 -0.305054)
			(stroke
				(width 0.1)
				(type default)
			)
			(layer "B.Fab")
		)
		(fp_line
			(start -0.120396 0.2794)
			(end 0.12065 0.2794)
			(stroke
				(width 0.1)
				(type default)
			)
			(layer "B.Fab")
		)
		(fp_line
			(start 0.12065 0.2794)
			(end 0.12065 0.3048)
			(stroke
				(width 0.1)
				(type default)
			)
			(layer "B.Fab")
		)
		(fp_line
			(start -0.12065 -0.2794)
			(end -0.12065 -0.3048)
			(stroke
				(width 0.1)
				(type default)
			)
			(layer "B.Fab")
		)
		(fp_line
			(start 0.12065 -0.2794)
			(end -0.12065 -0.2794)
			(stroke
				(width 0.1)
				(type default)
			)
			(layer "B.Fab")
		)
		(fp_line
			(start -0.67945 -0.3048)
			(end -0.67945 0.3048)
			(stroke
				(width 0.1)
				(type default)
			)
			(layer "B.Fab")
		)
		(fp_line
			(start -0.12065 -0.3048)
			(end -0.67945 -0.3048)
			(stroke
				(width 0.1)
				(type default)
			)
			(layer "B.Fab")
		)
		(fp_line
			(start 0.12065 -0.305054)
			(end 0.12065 -0.2794)
			(stroke
				(width 0.1)
				(type default)
			)
			(layer "B.Fab")
		)
		(fp_line
			(start 0.67945 -0.305054)
			(end 0.12065 -0.305054)
			(stroke
				(width 0.1)
				(type default)
			)
			(layer "B.Fab")
		)
		(pad "1" smd circle
			(at 0.40005 0 90)
			(size 0 0)
			(layers "B.Cu" "B.Mask" "B.Paste")
			(net "I3C_SPD_DDRABCD_CPU0_R_SCL")
		)
		(pad "2" smd circle
			(at -0.40005 0 90)
			(size 0 0)
			(layers "B.Cu" "B.Mask" "B.Paste")
			(net "I3C_SPD_DDRABCD_CPU0_LVC1_R_SCL")
		)
	)
	(footprint ""
		(layer "B.Cu")
		(at 501.233948 -303.58334 -90)
		(property "Reference" "X26"
			(at 3.427476 3.336798 270)
			(unlocked yes)
			(layer "B.SilkS")
			(effects
				(font
					(size 0.7874 0.5842)
					(thickness 0.1524)
				)
				(justify left mirror)
			)
		)
		(property "Value" ""
			(at 0 0 90)
			(layer "B.Fab")
			(effects
				(font
					(size 1.27 1.27)
				)
				(justify mirror)
			)
		)
		(property "Device Type" "TP_TDR_4P_FTS_TH-TP_TDR_4P_DIPA"
			(at -1.30175 1.27 180)
			(unlocked yes)
			(layer "B.Fab")
			(hide yes)
			(effects
				(font
					(size 0.635 0.4064)
					(thickness 0.1524)
				)
				(justify mirror)
			)
		)
		(property "User Part Number" "N_A"
			(at -1.30175 1.27 180)
			(unlocked yes)
			(layer "Cmts.User")
			(hide yes)
			(effects
				(font
					(size 0.635 0.4064)
					(thickness 0.1524)
				)
				(justify mirror)
			)
		)
		(duplicate_pad_numbers_are_jumpers no)
		(fp_line
			(start -2.54 3.81)
			(end -2.54 3.6703)
			(stroke
				(width 0.1524)
				(type default)
			)
			(layer "B.SilkS")
		)
		(fp_line
			(start 0 3.81)
			(end -2.54 3.81)
			(stroke
				(width 0.1524)
				(type default)
			)
			(layer "B.SilkS")
		)
		(fp_line
			(start 0 3.175)
			(end 0 3.81)
			(stroke
				(width 0.1524)
				(type default)
			)
			(layer "B.SilkS")
		)
		(fp_line
			(start -2.54 1.4097)
			(end -2.54 1.1303)
			(stroke
				(width 0.1524)
				(type default)
			)
			(layer "B.SilkS")
		)
		(fp_line
			(start 0 0.635)
			(end 0 1.905)
			(stroke
				(width 0.1524)
				(type default)
			)
			(layer "B.SilkS")
		)
		(fp_line
			(start -2.54 -1.1303)
			(end -2.54 -1.27)
			(stroke
				(width 0.1524)
				(type default)
			)
			(layer "B.SilkS")
		)
		(fp_line
			(start -2.54 -1.27)
			(end 0 -1.27)
			(stroke
				(width 0.1524)
				(type default)
			)
			(layer "B.SilkS")
		)
		(fp_line
			(start 0 -1.27)
			(end 0 -0.635)
			(stroke
				(width 0.1524)
				(type default)
			)
			(layer "B.SilkS")
		)
		(fp_poly
			(pts
				(xy 3.043428 -0.804164) (xy 3.043428 0.719836) (xy 1.519428 -0.042164)
			)
			(stroke
				(width 0)
				(type default)
			)
			(fill yes)
			(layer "B.SilkS")
		)
		(fp_line
			(start -2.54 3.81)
			(end -2.54 -1.27)
			(stroke
				(width 0.1)
				(type default)
			)
			(layer "B.Fab")
		)
		(fp_line
			(start 0 3.81)
			(end -2.54 3.81)
			(stroke
				(width 0.1)
				(type default)
			)
			(layer "B.Fab")
		)
		(fp_line
			(start -2.54 -1.27)
			(end 0 -1.27)
			(stroke
				(width 0.1)
				(type default)
			)
			(layer "B.Fab")
		)
		(fp_line
			(start 0 -1.27)
			(end 0 3.81)
			(stroke
				(width 0.1)
				(type default)
			)
			(layer "B.Fab")
		)
		(fp_poly
			(pts
				(xy 0.761746 0) (xy 2.285746 -0.762) (xy 2.285746 0.762)
			)
			(stroke
				(width 0)
				(type default)
			)
			(fill yes)
			(layer "B.Fab")
		)
		(pad "1" thru_hole circle
			(at 0 0 90)
			(size 1.0033 1.0033)
			(drill 0.249936)
			(layers "*.Cu" "*.Mask")
			(remove_unused_layers no)
			(net "TDR_DIFF_85_IN6_DP")
			(clearance 0.10795)
			(padstack
				(mode front_inner_back)
				(layer "Inner"
					(shape circle)
					(size 0.8001 0.8001)
					(clearance 0.1524)
				)
				(layer "B.Cu"
					(shape circle)
					(size 1.0033 1.0033)
					(thermal_gap 0.10795)
					(clearance 0.10795)
				)
			)
		)
		(pad "2" thru_hole circle
			(at -2.54 0 90)
			(size 1.9939 1.9939)
			(drill 0.249936)
			(layers "*.Cu" "*.Mask")
			(remove_unused_layers no)
			(net "T1_GND")
			(clearance 0.10795)
			(padstack
				(mode front_inner_back)
				(layer "Inner"
					(shape circle)
					(size 0.8001 0.8001)
					(clearance 0.1524)
				)
				(layer "B.Cu"
					(shape circle)
					(size 1.9939 1.9939)
					(thermal_gap 0.10795)
					(clearance 0.10795)
				)
			)
		)
		(pad "3" thru_hole circle
			(at -2.54 2.54 90)
			(size 1.9939 1.9939)
			(drill 0.249936)
			(layers "*.Cu" "*.Mask")
			(remove_unused_layers no)
			(net "T1_GND")
			(clearance 0.10795)
			(padstack
				(mode front_inner_back)
				(layer "Inner"
					(shape circle)
					(size 0.8001 0.8001)
					(clearance 0.1524)
				)
				(layer "B.Cu"
					(shape circle)
					(size 1.9939 1.9939)
					(thermal_gap 0.10795)
					(clearance 0.10795)
				)
			)
		)
		(pad "4" thru_hole circle
			(at 0 2.54 90)
			(size 1.0033 1.0033)
			(drill 0.249936)
			(layers "*.Cu" "*.Mask")
			(remove_unused_layers no)
			(net "TDR_DIFF_85_IN6_DN")
			(clearance 0.10795)
			(padstack
				(mode front_inner_back)
				(layer "Inner"
					(shape circle)
					(size 0.8001 0.8001)
					(clearance 0.1524)
				)
				(layer "B.Cu"
					(shape circle)
					(size 1.0033 1.0033)
					(thermal_gap 0.10795)
					(clearance 0.10795)
				)
			)
		)
	)
)
